(kicad_pcb
	(version 20260206)
	(generator "pcbnew")
	(generator_version "10.0")
	(general
		(thickness 1.6)
		(legacy_teardrops no)
	)
	(paper "A4")
	(title_block
		(title "01162023_DA0F0TEBIF0_F0T_Expander_BD_F_brd_V02_OCP.brd")
		(comment 1 "Grand Teton / footprints 6058-6063 of 9728")
	)
	(layers
		(0 "F.Cu" signal "TOP")
		(4 "In1.Cu" signal "GND")
		(6 "In2.Cu" signal "VCC")
		(8 "In3.Cu" signal "VCC1")
		(10 "In4.Cu" signal "GND1")
		(12 "In5.Cu" signal "IN1")
		(14 "In6.Cu" signal "GND2")
		(16 "In7.Cu" signal "IN2")
		(18 "In8.Cu" signal "GND3")
		(20 "In9.Cu" signal "IN3")
		(22 "In10.Cu" signal "GND4")
		(24 "In11.Cu" signal "IN4")
		(26 "In12.Cu" signal "GND5")
		(28 "In13.Cu" signal "IN5")
		(30 "In14.Cu" signal "GND6")
		(32 "In15.Cu" signal "IN6")
		(34 "In16.Cu" signal "GND7")
		(2 "B.Cu" signal "BOTTOM")
		(9 "F.Adhes" user "F.Adhesive")
		(11 "B.Adhes" user "B.Adhesive")
		(13 "F.Paste" user "Package Geometry/Pastemask Top")
		(15 "B.Paste" user "Package Geometry/Pastemask Bottom")
		(5 "F.SilkS" user "Ref Des/Silkscreen Top")
		(7 "B.SilkS" user "Ref Des/Silkscreen Bottom")
		(1 "F.Mask" user "Board Geometry/Soldermask Top")
		(3 "B.Mask" user "Board Geometry/Soldermask Bottom")
		(17 "Dwgs.User" user "User.Drawings")
		(19 "Cmts.User" user "User.Comments")
		(21 "Eco1.User" user "User.Eco1")
		(23 "Eco2.User" user "User.Eco2")
		(25 "Edge.Cuts" user "Board Geometry/Outline")
		(27 "Margin" user)
		(31 "F.CrtYd" user "Package Geometry/Place Bound Top")
		(29 "B.CrtYd" user "Package Geometry/Place Bound Bottom")
		(35 "F.Fab" user "Ref Des/Assembly Top")
		(33 "B.Fab" user "Ref Des/Assembly Bottom")
	)
	(footprint ""
		(layer "F.Cu")
		(at 117.117114 -260.671564 90)
		(property "Reference" "PC50"
			(at 0 0 90)
			(layer "F.SilkS")
			(hide yes)
			(effects
				(font
					(size 1.27 1.27)
				)
			)
		)
		(property "Value" ""
			(at 0 0 90)
			(layer "F.Fab")
			(effects
				(font
					(size 1.27 1.27)
				)
			)
		)
		(duplicate_pad_numbers_are_jumpers no)
		(fp_line
			(start 0.7874 -0.4064)
			(end 0.7874 0.4064)
			(stroke
				(width 0.1524)
				(type default)
			)
			(layer "F.SilkS")
		)
		(fp_line
			(start -0.7874 -0.4064)
			(end 0.7874 -0.4064)
			(stroke
				(width 0.1524)
				(type default)
			)
			(layer "F.SilkS")
		)
		(fp_line
			(start 0.7874 0.4064)
			(end -0.7874 0.4064)
			(stroke
				(width 0.1524)
				(type default)
			)
			(layer "F.SilkS")
		)
		(fp_line
			(start -0.7874 0.4064)
			(end -0.7874 -0.4064)
			(stroke
				(width 0.1524)
				(type default)
			)
			(layer "F.SilkS")
		)
		(fp_line
			(start -0.12065 -0.305054)
			(end -0.12065 -0.2794)
			(stroke
				(width 0.1)
				(type default)
			)
			(layer "F.Fab")
		)
		(fp_line
			(start -0.67945 -0.305054)
			(end -0.12065 -0.305054)
			(stroke
				(width 0.1)
				(type default)
			)
			(layer "F.Fab")
		)
		(fp_line
			(start 0.67945 -0.3048)
			(end 0.67945 0.3048)
			(stroke
				(width 0.1)
				(type default)
			)
			(layer "F.Fab")
		)
		(fp_line
			(start 0.12065 -0.3048)
			(end 0.67945 -0.3048)
			(stroke
				(width 0.1)
				(type default)
			)
			(layer "F.Fab")
		)
		(fp_line
			(start 0.12065 -0.2794)
			(end 0.12065 -0.3048)
			(stroke
				(width 0.1)
				(type default)
			)
			(layer "F.Fab")
		)
		(fp_line
			(start -0.12065 -0.2794)
			(end 0.12065 -0.2794)
			(stroke
				(width 0.1)
				(type default)
			)
			(layer "F.Fab")
		)
		(fp_line
			(start 0.120396 0.2794)
			(end -0.12065 0.2794)
			(stroke
				(width 0.1)
				(type default)
			)
			(layer "F.Fab")
		)
		(fp_line
			(start -0.12065 0.2794)
			(end -0.12065 0.3048)
			(stroke
				(width 0.1)
				(type default)
			)
			(layer "F.Fab")
		)
		(fp_line
			(start 0.67945 0.3048)
			(end 0.120396 0.3048)
			(stroke
				(width 0.1)
				(type default)
			)
			(layer "F.Fab")
		)
		(fp_line
			(start 0.120396 0.3048)
			(end 0.120396 0.2794)
			(stroke
				(width 0.1)
				(type default)
			)
			(layer "F.Fab")
		)
		(fp_line
			(start -0.12065 0.3048)
			(end -0.67945 0.3048)
			(stroke
				(width 0.1)
				(type default)
			)
			(layer "F.Fab")
		)
		(fp_line
			(start -0.67945 0.3048)
			(end -0.67945 -0.305054)
			(stroke
				(width 0.1)
				(type default)
			)
			(layer "F.Fab")
		)
		(pad "1" smd circle
			(at -0.40005 0 90)
			(size 0 0)
			(layers "F.Cu" "F.Mask" "F.Paste")
			(net "P0V8_PEX1_VSEN1")
		)
		(pad "2" smd circle
			(at 0.40005 0 90)
			(size 0 0)
			(layers "F.Cu" "F.Mask" "F.Paste")
			(net "SH_P0V8_PEX1_RGND1")
		)
	)
	(footprint ""
		(layer "F.Cu")
		(at 205.95209 -289.230816 90)
		(property "Reference" "R3938"
			(at 0 0 90)
			(layer "F.SilkS")
			(hide yes)
			(effects
				(font
					(size 1.27 1.27)
				)
			)
		)
		(property "Value" ""
			(at 0 0 90)
			(layer "F.Fab")
			(effects
				(font
					(size 1.27 1.27)
				)
			)
		)
		(duplicate_pad_numbers_are_jumpers no)
		(fp_line
			(start 0.7874 -0.4064)
			(end 0.7874 0.4064)
			(stroke
				(width 0.1524)
				(type default)
			)
			(layer "F.SilkS")
		)
		(fp_line
			(start -0.7874 -0.4064)
			(end 0.7874 -0.4064)
			(stroke
				(width 0.1524)
				(type default)
			)
			(layer "F.SilkS")
		)
		(fp_line
			(start 0.7874 0.4064)
			(end -0.7874 0.4064)
			(stroke
				(width 0.1524)
				(type default)
			)
			(layer "F.SilkS")
		)
		(fp_line
			(start -0.7874 0.4064)
			(end -0.7874 -0.4064)
			(stroke
				(width 0.1524)
				(type default)
			)
			(layer "F.SilkS")
		)
		(fp_line
			(start -0.12065 -0.305054)
			(end -0.12065 -0.2794)
			(stroke
				(width 0.1)
				(type default)
			)
			(layer "F.Fab")
		)
		(fp_line
			(start -0.67945 -0.305054)
			(end -0.12065 -0.305054)
			(stroke
				(width 0.1)
				(type default)
			)
			(layer "F.Fab")
		)
		(fp_line
			(start 0.67945 -0.3048)
			(end 0.67945 0.3048)
			(stroke
				(width 0.1)
				(type default)
			)
			(layer "F.Fab")
		)
		(fp_line
			(start 0.12065 -0.3048)
			(end 0.67945 -0.3048)
			(stroke
				(width 0.1)
				(type default)
			)
			(layer "F.Fab")
		)
		(fp_line
			(start 0.12065 -0.2794)
			(end 0.12065 -0.3048)
			(stroke
				(width 0.1)
				(type default)
			)
			(layer "F.Fab")
		)
		(fp_line
			(start -0.12065 -0.2794)
			(end 0.12065 -0.2794)
			(stroke
				(width 0.1)
				(type default)
			)
			(layer "F.Fab")
		)
		(fp_line
			(start 0.120396 0.2794)
			(end -0.12065 0.2794)
			(stroke
				(width 0.1)
				(type default)
			)
			(layer "F.Fab")
		)
		(fp_line
			(start -0.12065 0.2794)
			(end -0.12065 0.3048)
			(stroke
				(width 0.1)
				(type default)
			)
			(layer "F.Fab")
		)
		(fp_line
			(start 0.67945 0.3048)
			(end 0.120396 0.3048)
			(stroke
				(width 0.1)
				(type default)
			)
			(layer "F.Fab")
		)
		(fp_line
			(start 0.120396 0.3048)
			(end 0.120396 0.2794)
			(stroke
				(width 0.1)
				(type default)
			)
			(layer "F.Fab")
		)
		(fp_line
			(start -0.12065 0.3048)
			(end -0.67945 0.3048)
			(stroke
				(width 0.1)
				(type default)
			)
			(layer "F.Fab")
		)
		(fp_line
			(start -0.67945 0.3048)
			(end -0.67945 -0.305054)
			(stroke
				(width 0.1)
				(type default)
			)
			(layer "F.Fab")
		)
		(pad "1" smd circle
			(at -0.40005 0 90)
			(size 0 0)
			(layers "F.Cu" "F.Mask" "F.Paste")
			(net "SMB_PEX1_PCA9555_SDA")
		)
		(pad "2" smd circle
			(at 0.40005 0 90)
			(size 0 0)
			(layers "F.Cu" "F.Mask" "F.Paste")
			(net "SMB_PEX1_HOST_LS_SDA")
		)
	)
	(footprint ""
		(layer "F.Cu")
		(at 129.690114 -255.210564 180)
		(property "Reference" "R827"
			(at 0 0 180)
			(layer "F.SilkS")
			(hide yes)
			(effects
				(font
					(size 1.27 1.27)
				)
			)
		)
		(property "Value" ""
			(at 0 0 180)
			(layer "F.Fab")
			(effects
				(font
					(size 1.27 1.27)
				)
			)
		)
		(duplicate_pad_numbers_are_jumpers no)
		(fp_line
			(start 0.7874 0.4064)
			(end -0.7874 0.4064)
			(stroke
				(width 0.1524)
				(type default)
			)
			(layer "F.SilkS")
		)
		(fp_line
			(start 0.7874 -0.4064)
			(end 0.7874 0.4064)
			(stroke
				(width 0.1524)
				(type default)
			)
			(layer "F.SilkS")
		)
		(fp_line
			(start -0.7874 0.4064)
			(end -0.7874 -0.4064)
			(stroke
				(width 0.1524)
				(type default)
			)
			(layer "F.SilkS")
		)
		(fp_line
			(start -0.7874 -0.4064)
			(end 0.7874 -0.4064)
			(stroke
				(width 0.1524)
				(type default)
			)
			(layer "F.SilkS")
		)
		(fp_line
			(start 0.67945 0.3048)
			(end 0.120396 0.3048)
			(stroke
				(width 0.1)
				(type default)
			)
			(layer "F.Fab")
		)
		(fp_line
			(start 0.67945 -0.3048)
			(end 0.67945 0.3048)
			(stroke
				(width 0.1)
				(type default)
			)
			(layer "F.Fab")
		)
		(fp_line
			(start 0.12065 -0.2794)
			(end 0.12065 -0.3048)
			(stroke
				(width 0.1)
				(type default)
			)
			(layer "F.Fab")
		)
		(fp_line
			(start 0.12065 -0.3048)
			(end 0.67945 -0.3048)
			(stroke
				(width 0.1)
				(type default)
			)
			(layer "F.Fab")
		)
		(fp_line
			(start 0.120396 0.3048)
			(end 0.120396 0.2794)
			(stroke
				(width 0.1)
				(type default)
			)
			(layer "F.Fab")
		)
		(fp_line
			(start 0.120396 0.2794)
			(end -0.12065 0.2794)
			(stroke
				(width 0.1)
				(type default)
			)
			(layer "F.Fab")
		)
		(fp_line
			(start -0.12065 0.3048)
			(end -0.67945 0.3048)
			(stroke
				(width 0.1)
				(type default)
			)
			(layer "F.Fab")
		)
		(fp_line
			(start -0.12065 0.2794)
			(end -0.12065 0.3048)
			(stroke
				(width 0.1)
				(type default)
			)
			(layer "F.Fab")
		)
		(fp_line
			(start -0.12065 -0.2794)
			(end 0.12065 -0.2794)
			(stroke
				(width 0.1)
				(type default)
			)
			(layer "F.Fab")
		)
		(fp_line
			(start -0.12065 -0.305054)
			(end -0.12065 -0.2794)
			(stroke
				(width 0.1)
				(type default)
			)
			(layer "F.Fab")
		)
		(fp_line
			(start -0.67945 0.3048)
			(end -0.67945 -0.305054)
			(stroke
				(width 0.1)
				(type default)
			)
			(layer "F.Fab")
		)
		(fp_line
			(start -0.67945 -0.305054)
			(end -0.12065 -0.305054)
			(stroke
				(width 0.1)
				(type default)
			)
			(layer "F.Fab")
		)
		(pad "1" smd circle
			(at -0.40005 0 180)
			(size 0 0)
			(layers "F.Cu" "F.Mask" "F.Paste")
			(net "PWR_EN_PEX_R")
		)
		(pad "2" smd circle
			(at 0.40005 0 180)
			(size 0 0)
			(layers "F.Cu" "F.Mask" "F.Paste")
			(net "FM_P0V8_PEX0_EN_R")
		)
	)
	(footprint ""
		(layer "F.Cu")
		(at 10.420858 -317.105792 180)
		(property "Reference" "PC203"
			(at 0 0 180)
			(layer "F.SilkS")
			(hide yes)
			(effects
				(font
					(size 1.27 1.27)
				)
			)
		)
		(property "Value" ""
			(at 0 0 180)
			(layer "F.Fab")
			(effects
				(font
					(size 1.27 1.27)
				)
			)
		)
		(duplicate_pad_numbers_are_jumpers no)
		(fp_line
			(start 0.7874 0.4064)
			(end -0.7874 0.4064)
			(stroke
				(width 0.1524)
				(type default)
			)
			(layer "F.SilkS")
		)
		(fp_line
			(start 0.7874 -0.4064)
			(end 0.7874 0.4064)
			(stroke
				(width 0.1524)
				(type default)
			)
			(layer "F.SilkS")
		)
		(fp_line
			(start -0.7874 0.4064)
			(end -0.7874 -0.4064)
			(stroke
				(width 0.1524)
				(type default)
			)
			(layer "F.SilkS")
		)
		(fp_line
			(start -0.7874 -0.4064)
			(end 0.7874 -0.4064)
			(stroke
				(width 0.1524)
				(type default)
			)
			(layer "F.SilkS")
		)
		(fp_line
			(start 0.67945 0.3048)
			(end 0.120396 0.3048)
			(stroke
				(width 0.1)
				(type default)
			)
			(layer "F.Fab")
		)
		(fp_line
			(start 0.67945 -0.3048)
			(end 0.67945 0.3048)
			(stroke
				(width 0.1)
				(type default)
			)
			(layer "F.Fab")
		)
		(fp_line
			(start 0.12065 -0.2794)
			(end 0.12065 -0.3048)
			(stroke
				(width 0.1)
				(type default)
			)
			(layer "F.Fab")
		)
		(fp_line
			(start 0.12065 -0.3048)
			(end 0.67945 -0.3048)
			(stroke
				(width 0.1)
				(type default)
			)
			(layer "F.Fab")
		)
		(fp_line
			(start 0.120396 0.3048)
			(end 0.120396 0.2794)
			(stroke
				(width 0.1)
				(type default)
			)
			(layer "F.Fab")
		)
		(fp_line
			(start 0.120396 0.2794)
			(end -0.12065 0.2794)
			(stroke
				(width 0.1)
				(type default)
			)
			(layer "F.Fab")
		)
		(fp_line
			(start -0.12065 0.3048)
			(end -0.67945 0.3048)
			(stroke
				(width 0.1)
				(type default)
			)
			(layer "F.Fab")
		)
		(fp_line
			(start -0.12065 0.2794)
			(end -0.12065 0.3048)
			(stroke
				(width 0.1)
				(type default)
			)
			(layer "F.Fab")
		)
		(fp_line
			(start -0.12065 -0.2794)
			(end 0.12065 -0.2794)
			(stroke
				(width 0.1)
				(type default)
			)
			(layer "F.Fab")
		)
		(fp_line
			(start -0.12065 -0.305054)
			(end -0.12065 -0.2794)
			(stroke
				(width 0.1)
				(type default)
			)
			(layer "F.Fab")
		)
		(fp_line
			(start -0.67945 0.3048)
			(end -0.67945 -0.305054)
			(stroke
				(width 0.1)
				(type default)
			)
			(layer "F.Fab")
		)
		(fp_line
			(start -0.67945 -0.305054)
			(end -0.12065 -0.305054)
			(stroke
				(width 0.1)
				(type default)
			)
			(layer "F.Fab")
		)
		(pad "1" smd circle
			(at -0.40005 0 180)
			(size 0 0)
			(layers "F.Cu" "F.Mask" "F.Paste")
			(net "P12V_AUX")
		)
		(pad "2" smd circle
			(at 0.40005 0 180)
			(size 0 0)
			(layers "F.Cu" "F.Mask" "F.Paste")
			(net "GND")
		)
	)
	(footprint ""
		(layer "F.Cu")
		(at 124.210572 -63.652146 180)
		(property "Reference" "R5976"
			(at 0 0 180)
			(layer "F.SilkS")
			(hide yes)
			(effects
				(font
					(size 1.27 1.27)
				)
			)
		)
		(property "Value" ""
			(at 0 0 180)
			(layer "F.Fab")
			(effects
				(font
					(size 1.27 1.27)
				)
			)
		)
		(duplicate_pad_numbers_are_jumpers no)
		(fp_line
			(start 0.7874 0.4064)
			(end -0.7874 0.4064)
			(stroke
				(width 0.1524)
				(type default)
			)
			(layer "F.SilkS")
		)
		(fp_line
			(start 0.7874 -0.4064)
			(end 0.7874 0.4064)
			(stroke
				(width 0.1524)
				(type default)
			)
			(layer "F.SilkS")
		)
		(fp_line
			(start -0.7874 0.4064)
			(end -0.7874 -0.4064)
			(stroke
				(width 0.1524)
				(type default)
			)
			(layer "F.SilkS")
		)
		(fp_line
			(start -0.7874 -0.4064)
			(end 0.7874 -0.4064)
			(stroke
				(width 0.1524)
				(type default)
			)
			(layer "F.SilkS")
		)
		(fp_line
			(start 0.67945 0.3048)
			(end 0.120396 0.3048)
			(stroke
				(width 0.1)
				(type default)
			)
			(layer "F.Fab")
		)
		(fp_line
			(start 0.67945 -0.3048)
			(end 0.67945 0.3048)
			(stroke
				(width 0.1)
				(type default)
			)
			(layer "F.Fab")
		)
		(fp_line
			(start 0.12065 -0.2794)
			(end 0.12065 -0.3048)
			(stroke
				(width 0.1)
				(type default)
			)
			(layer "F.Fab")
		)
		(fp_line
			(start 0.12065 -0.3048)
			(end 0.67945 -0.3048)
			(stroke
				(width 0.1)
				(type default)
			)
			(layer "F.Fab")
		)
		(fp_line
			(start 0.120396 0.3048)
			(end 0.120396 0.2794)
			(stroke
				(width 0.1)
				(type default)
			)
			(layer "F.Fab")
		)
		(fp_line
			(start 0.120396 0.2794)
			(end -0.12065 0.2794)
			(stroke
				(width 0.1)
				(type default)
			)
			(layer "F.Fab")
		)
		(fp_line
			(start -0.12065 0.3048)
			(end -0.67945 0.3048)
			(stroke
				(width 0.1)
				(type default)
			)
			(layer "F.Fab")
		)
		(fp_line
			(start -0.12065 0.2794)
			(end -0.12065 0.3048)
			(stroke
				(width 0.1)
				(type default)
			)
			(layer "F.Fab")
		)
		(fp_line
			(start -0.12065 -0.2794)
			(end 0.12065 -0.2794)
			(stroke
				(width 0.1)
				(type default)
			)
			(layer "F.Fab")
		)
		(fp_line
			(start -0.12065 -0.305054)
			(end -0.12065 -0.2794)
			(stroke
				(width 0.1)
				(type default)
			)
			(layer "F.Fab")
		)
		(fp_line
			(start -0.67945 0.3048)
			(end -0.67945 -0.305054)
			(stroke
				(width 0.1)
				(type default)
			)
			(layer "F.Fab")
		)
		(fp_line
			(start -0.67945 -0.305054)
			(end -0.12065 -0.305054)
			(stroke
				(width 0.1)
				(type default)
			)
			(layer "F.Fab")
		)
		(pad "1" smd circle
			(at -0.40005 0 180)
			(size 0 0)
			(layers "F.Cu" "F.Mask" "F.Paste")
			(net "P5V_AUX")
		)
		(pad "2" smd circle
			(at 0.40005 0 180)
			(size 0 0)
			(layers "F.Cu" "F.Mask" "F.Paste")
			(net "P12V_SSD4_PG_G2")
		)
	)
	(footprint ""
		(layer "F.Cu")
		(at 226.727512 -231.416606 -90)
		(property "Reference" "R4540"
			(at 0 0 270)
			(layer "F.SilkS")
			(hide yes)
			(effects
				(font
					(size 1.27 1.27)
				)
			)
		)
		(property "Value" ""
			(at 0 0 270)
			(layer "F.Fab")
			(effects
				(font
					(size 1.27 1.27)
				)
			)
		)
		(duplicate_pad_numbers_are_jumpers no)
		(fp_line
			(start -0.7874 0.4064)
			(end -0.7874 -0.4064)
			(stroke
				(width 0.1524)
				(type default)
			)
			(layer "F.SilkS")
		)
		(fp_line
			(start 0.7874 0.4064)
			(end -0.7874 0.4064)
			(stroke
				(width 0.1524)
				(type default)
			)
			(layer "F.SilkS")
		)
		(fp_line
			(start -0.7874 -0.4064)
			(end 0.7874 -0.4064)
			(stroke
				(width 0.1524)
				(type default)
			)
			(layer "F.SilkS")
		)
		(fp_line
			(start 0.7874 -0.4064)
			(end 0.7874 0.4064)
			(stroke
				(width 0.1524)
				(type default)
			)
			(layer "F.SilkS")
		)
		(fp_line
			(start -0.67945 0.3048)
			(end -0.67945 -0.305054)
			(stroke
				(width 0.1)
				(type default)
			)
			(layer "F.Fab")
		)
		(fp_line
			(start -0.12065 0.3048)
			(end -0.67945 0.3048)
			(stroke
				(width 0.1)
				(type default)
			)
			(layer "F.Fab")
		)
		(fp_line
			(start 0.120396 0.3048)
			(end 0.120396 0.2794)
			(stroke
				(width 0.1)
				(type default)
			)
			(layer "F.Fab")
		)
		(fp_line
			(start 0.67945 0.3048)
			(end 0.120396 0.3048)
			(stroke
				(width 0.1)
				(type default)
			)
			(layer "F.Fab")
		)
		(fp_line
			(start -0.12065 0.2794)
			(end -0.12065 0.3048)
			(stroke
				(width 0.1)
				(type default)
			)
			(layer "F.Fab")
		)
		(fp_line
			(start 0.120396 0.2794)
			(end -0.12065 0.2794)
			(stroke
				(width 0.1)
				(type default)
			)
			(layer "F.Fab")
		)
		(fp_line
			(start -0.12065 -0.2794)
			(end 0.12065 -0.2794)
			(stroke
				(width 0.1)
				(type default)
			)
			(layer "F.Fab")
		)
		(fp_line
			(start 0.12065 -0.2794)
			(end 0.12065 -0.3048)
			(stroke
				(width 0.1)
				(type default)
			)
			(layer "F.Fab")
		)
		(fp_line
			(start 0.12065 -0.3048)
			(end 0.67945 -0.3048)
			(stroke
				(width 0.1)
				(type default)
			)
			(layer "F.Fab")
		)
		(fp_line
			(start 0.67945 -0.3048)
			(end 0.67945 0.3048)
			(stroke
				(width 0.1)
				(type default)
			)
			(layer "F.Fab")
		)
		(fp_line
			(start -0.67945 -0.305054)
			(end -0.12065 -0.305054)
			(stroke
				(width 0.1)
				(type default)
			)
			(layer "F.Fab")
		)
		(fp_line
			(start -0.12065 -0.305054)
			(end -0.12065 -0.2794)
			(stroke
				(width 0.1)
				(type default)
			)
			(layer "F.Fab")
		)
		(pad "1" smd circle
			(at -0.40005 0 270)
			(size 0 0)
			(layers "F.Cu" "F.Mask" "F.Paste")
			(net "NIC4_MAIN_PWR_BIC_EN_R")
		)
		(pad "2" smd circle
			(at 0.40005 0 270)
			(size 0 0)
			(layers "F.Cu" "F.Mask" "F.Paste")
			(net "NIC4_MAIN_PWR_BIC_EN")
		)
	)
)
